FILE_TYPE = CONNECTIVITY;
{Allegro Design Entry HDL 17.2-2016 S081 (4005846) 1/11/2022}
"PAGE_NUMBER" = 208;
0"NC";
1"GND\g";
2"RST_PERST_SWB_N"CDS_PHYS_NET_NAME"RST_PERST_SWB_R_N";
3"FM_PVCCD_HV_CPU0_EN";
4"FM_PVCCIN_CPU1_R_EN";
5"PWRGD_DRAMPWRGD_CPU0_CD_R_LVC1"CDS_PHYS_NET_NAME"PWRGD_CPU1_LVC1_R";
6"RST_CPU1_LVC1_R_N"CDS_PHYS_NET_NAME"RST_CPU1_LVC1_R_N";
7"PWRGD_SYS_PWROK";
8"FM_PLD_CLK_25M_R_EN"CDS_PHYS_NET_NAME"FM_PLD_CLK_25M_R_EN";
9"PWRGD_CPU0_LVC1_R"CDS_PHYS_NET_NAME"PWRGD_CPU0_LVC1_R";
10"FM_AUX_SW_EN"CDS_PHYS_NET_NAME"FM_AUX_SW_EN";
11"PWRGD_DRAMPWRGD_CPU1_AB_R_LVC1"CDS_PHYS_NET_NAME"RST_SRST_BMC_PLD_N";
12"PWRGD_DRAMPWRGD_CPU1_CD_R_LVC1"CDS_PHYS_NET_NAME"PWRGD_CPU1_LVC1_R";
13"PWRGD_CPU1_LVC1_R";
14"PWRGD_PCH_PWROK";
15"FM_PCH_P1V8_AUX_EN";
16"FM_PVCCIN_CPU0_R_EN";
17"FM_PVCCFA_EHV_FIVRA_CPU1_R_EN";
18"FM_PVCCD_HV_CPU1_EN";
19"FM_PVCCFA_EHV_FIVRA_CPU0_R_EN";
20"FM_PVCCFA_EHV_CPU1_R_EN";
21"FM_PVCCFA_EHV_CPU0_R_EN";
22"FM_PVCCINFAON_CPU1_R_EN";
23"FM_PVCCINFAON_CPU0_R_EN";
24"PWRGD_DRAMPWRGD_CPU1_GH_R_LVC1"CDS_PHYS_NET_NAME"RST_SRST_BMC_PLD_N";
25"PWRGD_DRAMPWRGD_CPU1_EF_R_LVC1"CDS_PHYS_NET_NAME"PWRGD_CPU1_LVC1_R";
26"RST_CPU0_LVC1_R_N"CDS_PHYS_NET_NAME"RST_CPU0_LVC1_R_N";
27"RST_PCIE_CPU0_DEV_PERST_N";
28"RST_PCIE_CPU1_DEV_PERST_N";
29"RST_RSMRST_PLD_R_N"CDS_PHYS_NET_NAME"PWRGD_CPU1_LVC1_R";
30"PWRGD_DRAMPWRGD_CPU0_GH_R_LVC1"CDS_PHYS_NET_NAME"RST_SRST_BMC_PLD_N";
31"PWRGD_DRAMPWRGD_CPU0_EF_R_LVC1"CDS_PHYS_NET_NAME"PWRGD_CPU1_LVC1_R";
32"PWRGD_DRAMPWRGD_CPU0_AB_R_LVC1"CDS_PHYS_NET_NAME"PWRGD_CPU1_LVC1_R";
33"RST_PLTRST_PLD_B_N";
34"RST_PCIE_PCH_DEV_PERST_N"CDS_PHYS_NET_NAME"PWRGD_CPU1_LVC1_R";
%"Q_RES"
"1","(-300,3100)","0","pure_quanta","I10";
;
PART_NUMBER"CS22002FB07"
MATERIAL"CHIP"
TOLERANCE"1%"
VALUE"2K"
$LOCATION"R1421"
WATTAGE"1/16W"
PACK_TYPE"0402LF"
CDS_LIB"pure_quanta"
CDS_LOCATION"R1421"
$SEC"1"
CDS_SEC"1";
"B"
$PN"2"1;
"A"
$PN"1"29;
%"Q_RES"
"1","(-300,2525)","0","pure_quanta","I11";
;
PART_NUMBER"CS22002FB07"
TOLERANCE"1%"
MATERIAL"EMPTY"
VALUE"2K"
$LOCATION"R1326"
CDS_LIB"pure_quanta"
WATTAGE"1/16W"
PACK_TYPE"0402LF"
CDS_LOCATION"R1326"
$SEC"1"
CDS_SEC"1";
"B"
$PN"2"1;
"A"
$PN"1"5;
%"Q_RES"
"1","(-300,2675)","0","pure_quanta","I12";
;
PART_NUMBER"CS22002FB07"
TOLERANCE"1%"
MATERIAL"EMPTY"
VALUE"2K"
$LOCATION"R1302"
PACK_TYPE"0402LF"
WATTAGE"1/16W"
CDS_LIB"pure_quanta"
CDS_LOCATION"R1302"
$SEC"1"
CDS_SEC"1";
"B"
$PN"2"1;
"A"
$PN"1"32;
%"Q_RES"
"1","(-300,2225)","0","pure_quanta","I13";
;
PART_NUMBER"CS22002FB07"
VALUE"2K"
TOLERANCE"1%"
MATERIAL"EMPTY"
$LOCATION"R1328"
CDS_LIB"pure_quanta"
WATTAGE"1/16W"
PACK_TYPE"0402LF"
CDS_LOCATION"R1328"
$SEC"1"
CDS_SEC"1";
"B"
$PN"2"1;
"A"
$PN"1"30;
%"Q_RES"
"1","(-300,2375)","0","pure_quanta","I14";
;
PART_NUMBER"CS22002FB07"
TOLERANCE"1%"
VALUE"2K"
MATERIAL"EMPTY"
$LOCATION"R1327"
PACK_TYPE"0402LF"
WATTAGE"1/16W"
CDS_LIB"pure_quanta"
CDS_LOCATION"R1327"
$SEC"1"
CDS_SEC"1";
"B"
$PN"2"1;
"A"
$PN"1"31;
%"Q_RES"
"1","(-300,2075)","0","pure_quanta","I15";
;
PART_NUMBER"CS22002FB07"
VALUE"2K"
TOLERANCE"1%"
MATERIAL"EMPTY"
$LOCATION"R1329"
CDS_LIB"pure_quanta"
WATTAGE"1/16W"
PACK_TYPE"0402LF"
CDS_LOCATION"R1329"
$SEC"1"
CDS_SEC"1";
"B"
$PN"2"1;
"A"
$PN"1"11;
%"Q_RES"
"1","(-300,1925)","0","pure_quanta","I16";
;
PART_NUMBER"CS22002FB07"
VALUE"2K"
TOLERANCE"1%"
MATERIAL"EMPTY"
$LOCATION"R1330"
CDS_LIB"pure_quanta"
WATTAGE"1/16W"
PACK_TYPE"0402LF"
CDS_LOCATION"R1330"
$SEC"1"
CDS_SEC"1";
"B"
$PN"2"1;
"A"
$PN"1"12;
%"Q_RES"
"1","(-300,1775)","0","pure_quanta","I17";
;
PART_NUMBER"CS22002FB07"
VALUE"2K"
MATERIAL"EMPTY"
TOLERANCE"1%"
$LOCATION"R1388"
CDS_LIB"pure_quanta"
WATTAGE"1/16W"
PACK_TYPE"0402LF"
CDS_LOCATION"R1388"
$SEC"1"
CDS_SEC"1";
"B"
$PN"2"1;
"A"
$PN"1"25;
%"Q_RES"
"1","(-300,1250)","0","pure_quanta","I18";
;
PART_NUMBER"CS22002FB07"
MATERIAL"CHIP"
TOLERANCE"1%"
PACK_TYPE"0402LF"
VALUE"2K"
WATTAGE"1/16W"
$LOCATION"R990"
CDS_LIB"pure_quanta"
CDS_LOCATION"R990"
$SEC"1"
CDS_SEC"1";
"B"
$PN"2"1;
"A"
$PN"1"8;
%"Q_RES"
"1","(-300,1625)","0","pure_quanta","I19";
;
PART_NUMBER"CS22002FB07"
VALUE"2K"
TOLERANCE"1%"
MATERIAL"EMPTY"
$LOCATION"R4533"
CDS_LIB"pure_quanta"
WATTAGE"1/16W"
PACK_TYPE"0402LF"
CDS_LOCATION"R4533"
$SEC"1"
CDS_SEC"1";
"B"
$PN"2"1;
"A"
$PN"1"24;
%"Q_RES"
"1","(-300,1100)","0","pure_quanta","I20";
;
PART_NUMBER"CS22002FB07"
MATERIAL"CHIP"
TOLERANCE"1%"
VALUE"2K"
$LOCATION"R991"
CDS_LIB"pure_quanta"
PACK_TYPE"0402LF"
WATTAGE"1/16W"
CDS_LOCATION"R991"
$SEC"1"
CDS_SEC"1";
"B"
$PN"2"1;
"A"
$PN"1"10;
%"Q_RES"
"1","(-300,950)","0","pure_quanta","I21";
;
PART_NUMBER"CS22002FB07"
TOLERANCE"1%"
VALUE"2K"
MATERIAL"EMPTY"
$LOCATION"R992"
CDS_LIB"pure_quanta"
PACK_TYPE"0402LF"
WATTAGE"1/16W"
CDS_LOCATION"R992"
$SEC"1"
CDS_SEC"1";
"B"
$PN"2"1;
"A"
$PN"1"9;
%"Q_RES"
"1","(-300,800)","0","pure_quanta","I22";
;
PART_NUMBER"CS22002FB07"
TOLERANCE"1%"
VALUE"2K"
MATERIAL"EMPTY"
$LOCATION"R1398"
CDS_LIB"pure_quanta"
PACK_TYPE"0402LF"
WATTAGE"1/16W"
CDS_LOCATION"R1398"
$SEC"1"
CDS_SEC"1";
"B"
$PN"2"1;
"A"
$PN"1"13;
%"Q_RES"
"1","(-300,650)","0","pure_quanta","I23";
;
PART_NUMBER"CS22002FB07"
VALUE"2K"
MATERIAL"CHIP"
$LOCATION"R1402"
TOLERANCE"1%"
CDS_LIB"pure_quanta"
PACK_TYPE"0402LF"
WATTAGE"1/16W"
CDS_LOCATION"R1402"
$SEC"1"
CDS_SEC"1";
"B"
$PN"2"1;
"A"
$PN"1"7;
%"Q_RES"
"1","(-300,500)","0","pure_quanta","I24";
;
PART_NUMBER"CS22002FB07"
MATERIAL"CHIP"
VALUE"2K"
TOLERANCE"1%"
$LOCATION"R1403"
WATTAGE"1/16W"
PACK_TYPE"0402LF"
CDS_LIB"pure_quanta"
CDS_LOCATION"R1403"
$SEC"1"
CDS_SEC"1";
"B"
$PN"2"1;
"A"
$PN"1"14;
%"Q_RES"
"1","(-300,350)","0","pure_quanta","I25";
;
PART_NUMBER"CS22002FB07"
MATERIAL"CHIP"
VALUE"2K"
TOLERANCE"1%"
$LOCATION"R1404"
WATTAGE"1/16W"
PACK_TYPE"0402LF"
CDS_LIB"pure_quanta"
CDS_LOCATION"R1404"
$SEC"1"
CDS_SEC"1";
"B"
$PN"2"1;
"A"
$PN"1"15;
%"Q_RES"
"1","(-300,200)","0","pure_quanta","I26";
;
PART_NUMBER"CS22002FB07"
TOLERANCE"1%"
VALUE"2K"
MATERIAL"CHIP"
$LOCATION"R1405"
CDS_LIB"pure_quanta"
PACK_TYPE"0402LF"
WATTAGE"1/16W"
CDS_LOCATION"R1405"
$SEC"1"
CDS_SEC"1";
"B"
$PN"2"1;
"A"
$PN"1"16;
%"Q_RES"
"1","(-300,4000)","0","pure_quanta","I4";
;
PART_NUMBER"CS22002FB07"
VALUE"2K"
MATERIAL"EMPTY"
PACK_TYPE"0402LF"
WATTAGE"1/16W"
TOLERANCE"1%"
$LOCATION"R1415"
CDS_LIB"pure_quanta"
CDS_LOCATION"R1415"
$SEC"1"
CDS_SEC"1";
"B"
$PN"2"1;
"A"
$PN"1"26;
%"Q_RES"
"1","(-300,3850)","0","pure_quanta","I5";
;
PART_NUMBER"CS22002FB07"
TOLERANCE"1%"
MATERIAL"EMPTY"
VALUE"2K"
$LOCATION"R1416"
WATTAGE"1/16W"
PACK_TYPE"0402LF"
CDS_LIB"pure_quanta"
CDS_LOCATION"R1416"
$SEC"1"
CDS_SEC"1";
"B"
$PN"2"1;
"A"
$PN"1"6;
%"UNIVERSAL_GND"
"1","(250,-1325)","0","logical_power","I50";
;
CDS_LIB"logical_power"
HDL_POWER"GND"
ROOM"IO_SLOT";
"A"1;
%"Q_RES"
"1","(-300,50)","0","pure_quanta","I51";
;
PART_NUMBER"CS22002FB07"
VALUE"2K"
TOLERANCE"1%"
MATERIAL"CHIP"
$LOCATION"R1406"
WATTAGE"1/16W"
PACK_TYPE"0402LF"
CDS_LIB"pure_quanta"
CDS_LOCATION"R1406"
$SEC"1"
CDS_SEC"1";
"B"
$PN"2"1;
"A"
$PN"1"4;
%"Q_RES"
"1","(-300,-100)","0","pure_quanta","I52";
;
PART_NUMBER"CS22002FB07"
TOLERANCE"1%"
VALUE"2K"
MATERIAL"CHIP"
$LOCATION"R1407"
CDS_LIB"pure_quanta"
PACK_TYPE"0402LF"
WATTAGE"1/16W"
CDS_LOCATION"R1407"
$SEC"1"
CDS_SEC"1";
"B"
$PN"2"1;
"A"
$PN"1"23;
%"Q_RES"
"1","(-300,-250)","0","pure_quanta","I53";
;
PART_NUMBER"CS22002FB07"
VALUE"2K"
TOLERANCE"1%"
MATERIAL"CHIP"
$LOCATION"R1408"
WATTAGE"1/16W"
PACK_TYPE"0402LF"
CDS_LIB"pure_quanta"
CDS_LOCATION"R1408"
$SEC"1"
CDS_SEC"1";
"B"
$PN"2"1;
"A"
$PN"1"22;
%"Q_RES"
"1","(-300,-550)","0","pure_quanta","I54";
;
PART_NUMBER"CS22002FB07"
MATERIAL"CHIP"
VALUE"2K"
TOLERANCE"1%"
$LOCATION"R1410"
WATTAGE"1/16W"
PACK_TYPE"0402LF"
CDS_LIB"pure_quanta"
CDS_LOCATION"R1410"
$SEC"1"
CDS_SEC"1";
"B"
$PN"2"1;
"A"
$PN"1"20;
%"Q_RES"
"1","(-300,-400)","0","pure_quanta","I55";
;
PART_NUMBER"CS22002FB07"
TOLERANCE"1%"
VALUE"2K"
MATERIAL"CHIP"
$LOCATION"R1409"
CDS_LIB"pure_quanta"
PACK_TYPE"0402LF"
WATTAGE"1/16W"
CDS_LOCATION"R1409"
$SEC"1"
CDS_SEC"1";
"B"
$PN"2"1;
"A"
$PN"1"21;
%"Q_RES"
"1","(-300,-700)","0","pure_quanta","I56";
;
PART_NUMBER"CS22002FB07"
TOLERANCE"1%"
VALUE"2K"
MATERIAL"CHIP"
$LOCATION"R1411"
CDS_LIB"pure_quanta"
PACK_TYPE"0402LF"
WATTAGE"1/16W"
CDS_LOCATION"R1411"
$SEC"1"
CDS_SEC"1";
"B"
$PN"2"1;
"A"
$PN"1"19;
%"Q_RES"
"1","(-300,-850)","0","pure_quanta","I57";
;
PART_NUMBER"CS22002FB07"
VALUE"2K"
MATERIAL"CHIP"
TOLERANCE"1%"
$LOCATION"R1412"
WATTAGE"1/16W"
PACK_TYPE"0402LF"
CDS_LIB"pure_quanta"
CDS_LOCATION"R1412"
$SEC"1"
CDS_SEC"1";
"B"
$PN"2"1;
"A"
$PN"1"17;
%"Q_RES"
"1","(-300,-1150)","0","pure_quanta","I58";
;
PART_NUMBER"CS22002FB07"
TOLERANCE"1%"
MATERIAL"CHIP"
VALUE"2K"
$LOCATION"R1414"
WATTAGE"1/16W"
PACK_TYPE"0402LF"
CDS_LIB"pure_quanta"
CDS_LOCATION"R1414"
$SEC"1"
CDS_SEC"1";
"B"
$PN"2"1;
"A"
$PN"1"18;
%"Q_RES"
"1","(-300,-1000)","0","pure_quanta","I59";
;
PART_NUMBER"CS22002FB07"
TOLERANCE"1%"
VALUE"2K"
MATERIAL"CHIP"
$LOCATION"R1413"
CDS_LIB"pure_quanta"
PACK_TYPE"0402LF"
WATTAGE"1/16W"
CDS_LOCATION"R1413"
$SEC"1"
CDS_SEC"1";
"B"
$PN"2"1;
"A"
$PN"1"3;
%"Q_RES"
"1","(-300,3550)","0","pure_quanta","I6";
;
PART_NUMBER"CS22002FB07"
TOLERANCE"1%"
MATERIAL"CHIP"
VALUE"2K"
$LOCATION"R1418"
CDS_LIB"pure_quanta"
WATTAGE"1/16W"
PACK_TYPE"0402LF"
CDS_LOCATION"R1418"
$SEC"1"
CDS_SEC"1";
"B"
$PN"2"1;
"A"
$PN"1"28;
%"Q_RES"
"1","(-300,2950)","0","pure_quanta","I66";
;
PART_NUMBER"CS22002FB07"
TOLERANCE"1%"
MATERIAL"CHIP"
VALUE"2K"
$LOCATION"R4622"
WATTAGE"1/16W"
PACK_TYPE"0402LF"
CDS_LIB"pure_quanta"
CDS_LOCATION"R4622"
$SEC"1"
CDS_SEC"1";
"B"
$PN"2"1;
"A"
$PN"1"2;
%"Q_RES"
"1","(-300,3700)","0","pure_quanta","I7";
;
PART_NUMBER"CS22002FB07"
TOLERANCE"1%"
MATERIAL"CHIP"
VALUE"2K"
$LOCATION"R1417"
CDS_LIB"pure_quanta"
PACK_TYPE"0402LF"
WATTAGE"1/16W"
CDS_LOCATION"R1417"
$SEC"1"
CDS_SEC"1";
"B"
$PN"2"1;
"A"
$PN"1"27;
%"Q_RES"
"1","(-300,3400)","0","pure_quanta","I8";
;
PART_NUMBER"CS22002FB07"
TOLERANCE"1%"
VALUE"2K"
MATERIAL"CHIP"
$LOCATION"R1419"
CDS_LIB"pure_quanta"
PACK_TYPE"0402LF"
WATTAGE"1/16W"
CDS_LOCATION"R1419"
$SEC"1"
CDS_SEC"1";
"B"
$PN"2"1;
"A"
$PN"1"34;
%"Q_RES"
"1","(-300,3250)","0","pure_quanta","I9";
;
PART_NUMBER"CS22002FB07"
TOLERANCE"1%"
VALUE"2K"
MATERIAL"CHIP"
$LOCATION"R1420"
CDS_LIB"pure_quanta"
PACK_TYPE"0402LF"
WATTAGE"1/16W"
CDS_LOCATION"R1420"
$SEC"1"
CDS_SEC"1";
"B"
$PN"2"1;
"A"
$PN"1"33;
END.
